G04 ================== begin FILE IDENTIFICATION RECORD ==================*
G04 Layout Name:  15750-1.brd*
G04 Film Name:    TMASK*
G04 File Format:  Gerber RS274X*
G04 File Origin:  Cadence Allegro 16.5-S056*
G04 Origin Date:  Fri Dec 30 13:21:31 2016*
G04 *
G04 Layer:  VIA CLASS/SOLDERMASK_TOP*
G04 Layer:  PIN/SOLDERMASK_TOP*
G04 Layer:  PACKAGE GEOMETRY/SOLDERMASK_TOP*
G04 Layer:  DRAWING FORMAT/LAYER_PCB_STORY*
G04 Layer:  DRAWING FORMAT/LAYER_SOLDER_T*
G04 Layer:  BOARD GEOMETRY/SOLDERMASK_TOP*
G04 *
G04 Offset:    (0.00 0.00)*
G04 Mirror:    No*
G04 Mode:      Positive*
G04 Rotation:  0*
G04 FullContactRelief:  No*
G04 UndefLineWidth:     6.00*
G04 ================== end FILE IDENTIFICATION RECORD ====================*
%FSLAX35Y35*MOIN*%
%IR0*IPPOS*OFA0.00000B0.00000*MIA0B0*SFA1.00000B1.00000*%
%AMMACRO46*
4,1,40,.013,.017,
-.013,.017,
-.013695,.016939,
-.014368,.016759,
-.015,.016464,
-.015571,.016064,
-.016064,.015571,
-.016464,.015,
-.016759,.014368,
-.016939,.013695,
-.017,.013,
-.017,-.013,
-.016939,-.013695,
-.016759,-.014368,
-.016464,-.015,
-.016064,-.015571,
-.015571,-.016064,
-.015,-.016464,
-.014368,-.016759,
-.013695,-.016939,
-.013,-.017,
.013,-.017,
.013695,-.016939,
.014368,-.016759,
.015,-.016464,
.015571,-.016064,
.016064,-.015571,
.016464,-.015,
.016759,-.014368,
.016939,-.013695,
.017,-.013,
.017,.013,
.016939,.013695,
.016759,.014368,
.016464,.015,
.016064,.015571,
.015571,.016064,
.015,.016464,
.014368,.016759,
.013695,.016939,
.013,.017,
0.0*
%
%ADD46MACRO46*%
%AMMACRO24*
4,1,40,.017,-.013,
.017,.013,
.016939,.013695,
.016759,.014368,
.016464,.015,
.016064,.015571,
.015571,.016064,
.015,.016464,
.014368,.016759,
.013695,.016939,
.013,.017,
-.013,.017,
-.013695,.016939,
-.014368,.016759,
-.015,.016464,
-.015571,.016064,
-.016064,.015571,
-.016464,.015,
-.016759,.014368,
-.016939,.013695,
-.017,.013,
-.017,-.013,
-.016939,-.013695,
-.016759,-.014368,
-.016464,-.015,
-.016064,-.015571,
-.015571,-.016064,
-.015,-.016464,
-.014368,-.016759,
-.013695,-.016939,
-.013,-.017,
.013,-.017,
.013695,-.016939,
.014368,-.016759,
.015,-.016464,
.015571,-.016064,
.016064,-.015571,
.016464,-.015,
.016759,-.014368,
.016939,-.013695,
.017,-.013,
0.0*
%
%ADD24MACRO24*%
%ADD44R,.102X.053*%
%ADD25C,.022*%
%ADD52R,.108X.047*%
%ADD51C,.044*%
%ADD12C,.08*%
%ADD50C,.063*%
%ADD14C,.028*%
%ADD57C,.065*%
%ADD56C,.056*%
%ADD10C,.086*%
%AMMACRO40*
4,1,40,.011,-.007,
.011,.007,
.010939,.007695,
.010759,.008368,
.010464,.009,
.010064,.009571,
.009571,.010064,
.009,.010464,
.008368,.010759,
.007695,.010939,
.007,.011,
-.007,.011,
-.007695,.010939,
-.008368,.010759,
-.009,.010464,
-.009571,.010064,
-.010064,.009571,
-.010464,.009,
-.010759,.008368,
-.010939,.007695,
-.011,.007,
-.011,-.007,
-.010939,-.007695,
-.010759,-.008368,
-.010464,-.009,
-.010064,-.009571,
-.009571,-.010064,
-.009,-.010464,
-.008368,-.010759,
-.007695,-.010939,
-.007,-.011,
.007,-.011,
.007695,-.010939,
.008368,-.010759,
.009,-.010464,
.009571,-.010064,
.010064,-.009571,
.010464,-.009,
.010759,-.008368,
.010939,-.007695,
.011,-.007,
0.0*
%
%ADD40MACRO40*%
%AMMACRO16*
4,1,40,.007,.011,
-.007,.011,
-.007695,.010939,
-.008368,.010759,
-.009,.010464,
-.009571,.010064,
-.010064,.009571,
-.010464,.009,
-.010759,.008368,
-.010939,.007695,
-.011,.007,
-.011,-.007,
-.010939,-.007695,
-.010759,-.008368,
-.010464,-.009,
-.010064,-.009571,
-.009571,-.010064,
-.009,-.010464,
-.008368,-.010759,
-.007695,-.010939,
-.007,-.011,
.007,-.011,
.007695,-.010939,
.008368,-.010759,
.009,-.010464,
.009571,-.010064,
.010064,-.009571,
.010464,-.009,
.010759,-.008368,
.010939,-.007695,
.011,-.007,
.011,.007,
.010939,.007695,
.010759,.008368,
.010464,.009,
.010064,.009571,
.009571,.010064,
.009,.010464,
.008368,.010759,
.007695,.010939,
.007,.011,
0.0*
%
%ADD16MACRO16*%
%AMMACRO22*
4,1,20,-.047,-.032,
-.047,-.0155,
-.074,-.0155,
-.074,-.0045,
-.049,-.0045,
-.049,.0045,
-.074,.0045,
-.074,.0155,
-.047,.0155,
-.047,.032,
.047,.032,
.047,.0155,
.074,.0155,
.074,.0045,
.049,.0045,
.049,-.0045,
.074,-.0045,
.074,-.0155,
.047,-.0155,
.047,-.032,
-.047,-.032,
0.0*
%
%ADD22MACRO22*%
%AMMACRO32*
4,1,40,-.012,.008,
-.012,-.008,
-.011939,-.008695,
-.011759,-.009368,
-.011464,-.01,
-.011064,-.010571,
-.010571,-.011064,
-.01,-.011464,
-.009368,-.011759,
-.008695,-.011939,
-.008,-.012,
.008,-.012,
.008695,-.011939,
.009368,-.011759,
.01,-.011464,
.010571,-.011064,
.011064,-.010571,
.011464,-.01,
.011759,-.009368,
.011939,-.008695,
.012,-.008,
.012,.008,
.011939,.008695,
.011759,.009368,
.011464,.01,
.011064,.010571,
.010571,.011064,
.01,.011464,
.009368,.011759,
.008695,.011939,
.008,.012,
-.008,.012,
-.008695,.011939,
-.009368,.011759,
-.01,.011464,
-.010571,.011064,
-.011064,.010571,
-.011464,.01,
-.011759,.009368,
-.011939,.008695,
-.012,.008,
0.0*
%
%ADD32MACRO32*%
%AMMACRO21*
4,1,40,.008,.012,
-.008,.012,
-.008695,.011939,
-.009368,.011759,
-.01,.011464,
-.010571,.011064,
-.011064,.010571,
-.011464,.01,
-.011759,.009368,
-.011939,.008695,
-.012,.008,
-.012,-.008,
-.011939,-.008695,
-.011759,-.009368,
-.011464,-.01,
-.011064,-.010571,
-.010571,-.011064,
-.01,-.011464,
-.009368,-.011759,
-.008695,-.011939,
-.008,-.012,
.008,-.012,
.008695,-.011939,
.009368,-.011759,
.01,-.011464,
.010571,-.011064,
.011064,-.010571,
.011464,-.01,
.011759,-.009368,
.011939,-.008695,
.012,-.008,
.012,.008,
.011939,.008695,
.011759,.009368,
.011464,.01,
.011064,.010571,
.010571,.011064,
.01,.011464,
.009368,.011759,
.008695,.011939,
.008,.012,
0.0*
%
%ADD21MACRO21*%
%AMMACRO53*
4,1,40,-.017,.013,
-.017,-.013,
-.016939,-.013695,
-.016759,-.014368,
-.016464,-.015,
-.016064,-.015571,
-.015571,-.016064,
-.015,-.016464,
-.014368,-.016759,
-.013695,-.016939,
-.013,-.017,
.013,-.017,
.013695,-.016939,
.014368,-.016759,
.015,-.016464,
.015571,-.016064,
.016064,-.015571,
.016464,-.015,
.016759,-.014368,
.016939,-.013695,
.017,-.013,
.017,.013,
.016939,.013695,
.016759,.014368,
.016464,.015,
.016064,.015571,
.015571,.016064,
.015,.016464,
.014368,.016759,
.013695,.016939,
.013,.017,
-.013,.017,
-.013695,.016939,
-.014368,.016759,
-.015,.016464,
-.015571,.016064,
-.016064,.015571,
-.016464,.015,
-.016759,.014368,
-.016939,.013695,
-.017,.013,
0.0*
%
%ADD53MACRO53*%
%AMMACRO42*
4,1,6,.005,.0135,
.005,.0065,
.025,-.0135,
-.025,-.0135,
-.005,.0065,
-.005,.0135,
.005,.0135,
0.0*
%
%ADD42MACRO42*%
%AMMACRO41*
4,1,40,.011,-.007,
.011,.007,
.010939,.007695,
.010759,.008368,
.010464,.009,
.010064,.009571,
.009571,.010064,
.009,.010464,
.008368,.010759,
.007695,.010939,
.007,.011,
-.007,.011,
-.007695,.010939,
-.008368,.010759,
-.009,.010464,
-.009571,.010064,
-.010064,.009571,
-.010464,.009,
-.010759,.008368,
-.010939,.007695,
-.011,.007,
-.011,-.007,
-.010939,-.007695,
-.010759,-.008368,
-.010464,-.009,
-.010064,-.009571,
-.009571,-.010064,
-.009,-.010464,
-.008368,-.010759,
-.007695,-.010939,
-.007,-.011,
.007,-.011,
.007695,-.010939,
.008368,-.010759,
.009,-.010464,
.009571,-.010064,
.010064,-.009571,
.010464,-.009,
.010759,-.008368,
.010939,-.007695,
.011,-.007,
0.0*
%
%ADD41MACRO41*%
%AMMACRO17*
4,1,40,.007,.011,
-.007,.011,
-.007695,.010939,
-.008368,.010759,
-.009,.010464,
-.009571,.010064,
-.010064,.009571,
-.010464,.009,
-.010759,.008368,
-.010939,.007695,
-.011,.007,
-.011,-.007,
-.010939,-.007695,
-.010759,-.008368,
-.010464,-.009,
-.010064,-.009571,
-.009571,-.010064,
-.009,-.010464,
-.008368,-.010759,
-.007695,-.010939,
-.007,-.011,
.007,-.011,
.007695,-.010939,
.008368,-.010759,
.009,-.010464,
.009571,-.010064,
.010064,-.009571,
.010464,-.009,
.010759,-.008368,
.010939,-.007695,
.011,-.007,
.011,.007,
.010939,.007695,
.010759,.008368,
.010464,.009,
.010064,.009571,
.009571,.010064,
.009,.010464,
.008368,.010759,
.007695,.010939,
.007,.011,
0.0*
%
%ADD17MACRO17*%
%AMMACRO31*
4,1,40,-.012,.008,
-.012,-.008,
-.011939,-.008695,
-.011759,-.009368,
-.011464,-.01,
-.011064,-.010571,
-.010571,-.011064,
-.01,-.011464,
-.009368,-.011759,
-.008695,-.011939,
-.008,-.012,
.008,-.012,
.008695,-.011939,
.009368,-.011759,
.01,-.011464,
.010571,-.011064,
.011064,-.010571,
.011464,-.01,
.011759,-.009368,
.011939,-.008695,
.012,-.008,
.012,.008,
.011939,.008695,
.011759,.009368,
.011464,.01,
.011064,.010571,
.010571,.011064,
.01,.011464,
.009368,.011759,
.008695,.011939,
.008,.012,
-.008,.012,
-.008695,.011939,
-.009368,.011759,
-.01,.011464,
-.010571,.011064,
-.011064,.010571,
-.011464,.01,
-.011759,.009368,
-.011939,.008695,
-.012,.008,
0.0*
%
%ADD31MACRO31*%
%AMMACRO20*
4,1,40,.008,.012,
-.008,.012,
-.008695,.011939,
-.009368,.011759,
-.01,.011464,
-.010571,.011064,
-.011064,.010571,
-.011464,.01,
-.011759,.009368,
-.011939,.008695,
-.012,.008,
-.012,-.008,
-.011939,-.008695,
-.011759,-.009368,
-.011464,-.01,
-.011064,-.010571,
-.010571,-.011064,
-.01,-.011464,
-.009368,-.011759,
-.008695,-.011939,
-.008,-.012,
.008,-.012,
.008695,-.011939,
.009368,-.011759,
.01,-.011464,
.010571,-.011064,
.011064,-.010571,
.011464,-.01,
.011759,-.009368,
.011939,-.008695,
.012,-.008,
.012,.008,
.011939,.008695,
.011759,.009368,
.011464,.01,
.011064,.010571,
.010571,.011064,
.01,.011464,
.009368,.011759,
.008695,.011939,
.008,.012,
0.0*
%
%ADD20MACRO20*%
%AMMACRO54*
4,1,40,-.017,.013,
-.017,-.013,
-.016939,-.013695,
-.016759,-.014368,
-.016464,-.015,
-.016064,-.015571,
-.015571,-.016064,
-.015,-.016464,
-.014368,-.016759,
-.013695,-.016939,
-.013,-.017,
.013,-.017,
.013695,-.016939,
.014368,-.016759,
.015,-.016464,
.015571,-.016064,
.016064,-.015571,
.016464,-.015,
.016759,-.014368,
.016939,-.013695,
.017,-.013,
.017,.013,
.016939,.013695,
.016759,.014368,
.016464,.015,
.016064,.015571,
.015571,.016064,
.015,.016464,
.014368,.016759,
.013695,.016939,
.013,.017,
-.013,.017,
-.013695,.016939,
-.014368,.016759,
-.015,.016464,
-.015571,.016064,
-.016064,.015571,
-.016464,.015,
-.016759,.014368,
-.016939,.013695,
-.017,.013,
0.0*
%
%ADD54MACRO54*%
%ADD35R,.06X.012*%
%ADD48R,.061X.012*%
%ADD30R,.012X.06*%
%ADD47R,.06X.014*%
%ADD39R,.044X.012*%
%ADD36R,.014X.06*%
%ADD18R,.012X.036*%
%ADD11C,.315*%
%ADD15R,.045X.055*%
%ADD55R,.016X.048*%
%ADD37R,.055X.045*%
%ADD49R,.095X.09*%
%AMMACRO33*
4,1,40,-.007,-.011,
.007,-.011,
.007695,-.010939,
.008368,-.010759,
.009,-.010464,
.009571,-.010064,
.010064,-.009571,
.010464,-.009,
.010759,-.008368,
.010939,-.007695,
.011,-.007,
.011,.007,
.010939,.007695,
.010759,.008368,
.010464,.009,
.010064,.009571,
.009571,.010064,
.009,.010464,
.008368,.010759,
.007695,.010939,
.007,.011,
-.007,.011,
-.007695,.010939,
-.008368,.010759,
-.009,.010464,
-.009571,.010064,
-.010064,.009571,
-.010464,.009,
-.010759,.008368,
-.010939,.007695,
-.011,.007,
-.011,-.007,
-.010939,-.007695,
-.010759,-.008368,
-.010464,-.009,
-.010064,-.009571,
-.009571,-.010064,
-.009,-.010464,
-.008368,-.010759,
-.007695,-.010939,
-.007,-.011,
0.0*
%
%ADD33MACRO33*%
%AMMACRO29*
4,1,40,-.008,-.012,
.008,-.012,
.008695,-.011939,
.009368,-.011759,
.01,-.011464,
.010571,-.011064,
.011064,-.010571,
.011464,-.01,
.011759,-.009368,
.011939,-.008695,
.012,-.008,
.012,.008,
.011939,.008695,
.011759,.009368,
.011464,.01,
.011064,.010571,
.010571,.011064,
.01,.011464,
.009368,.011759,
.008695,.011939,
.008,.012,
-.008,.012,
-.008695,.011939,
-.009368,.011759,
-.01,.011464,
-.010571,.011064,
-.011064,.010571,
-.011464,.01,
-.011759,.009368,
-.011939,.008695,
-.012,.008,
-.012,-.008,
-.011939,-.008695,
-.011759,-.009368,
-.011464,-.01,
-.011064,-.010571,
-.010571,-.011064,
-.01,-.011464,
-.009368,-.011759,
-.008695,-.011939,
-.008,-.012,
0.0*
%
%ADD29MACRO29*%
%AMMACRO13*
4,1,40,.012,-.008,
.012,.008,
.011939,.008695,
.011759,.009368,
.011464,.01,
.011064,.010571,
.010571,.011064,
.01,.011464,
.009368,.011759,
.008695,.011939,
.008,.012,
-.008,.012,
-.008695,.011939,
-.009368,.011759,
-.01,.011464,
-.010571,.011064,
-.011064,.010571,
-.011464,.01,
-.011759,.009368,
-.011939,.008695,
-.012,.008,
-.012,-.008,
-.011939,-.008695,
-.011759,-.009368,
-.011464,-.01,
-.011064,-.010571,
-.010571,-.011064,
-.01,-.011464,
-.009368,-.011759,
-.008695,-.011939,
-.008,-.012,
.008,-.012,
.008695,-.011939,
.009368,-.011759,
.01,-.011464,
.010571,-.011064,
.011064,-.010571,
.011464,-.01,
.011759,-.009368,
.011939,-.008695,
.012,-.008,
0.0*
%
%ADD13MACRO13*%
%AMMACRO26*
4,1,40,-.011,.007,
-.011,-.007,
-.010939,-.007695,
-.010759,-.008368,
-.010464,-.009,
-.010064,-.009571,
-.009571,-.010064,
-.009,-.010464,
-.008368,-.010759,
-.007695,-.010939,
-.007,-.011,
.007,-.011,
.007695,-.010939,
.008368,-.010759,
.009,-.010464,
.009571,-.010064,
.010064,-.009571,
.010464,-.009,
.010759,-.008368,
.010939,-.007695,
.011,-.007,
.011,.007,
.010939,.007695,
.010759,.008368,
.010464,.009,
.010064,.009571,
.009571,.010064,
.009,.010464,
.008368,.010759,
.007695,.010939,
.007,.011,
-.007,.011,
-.007695,.010939,
-.008368,.010759,
-.009,.010464,
-.009571,.010064,
-.010064,.009571,
-.010464,.009,
-.010759,.008368,
-.010939,.007695,
-.011,.007,
0.0*
%
%ADD26MACRO26*%
%AMMACRO45*
4,1,40,.013,.017,
-.013,.017,
-.013695,.016939,
-.014368,.016759,
-.015,.016464,
-.015571,.016064,
-.016064,.015571,
-.016464,.015,
-.016759,.014368,
-.016939,.013695,
-.017,.013,
-.017,-.013,
-.016939,-.013695,
-.016759,-.014368,
-.016464,-.015,
-.016064,-.015571,
-.015571,-.016064,
-.015,-.016464,
-.014368,-.016759,
-.013695,-.016939,
-.013,-.017,
.013,-.017,
.013695,-.016939,
.014368,-.016759,
.015,-.016464,
.015571,-.016064,
.016064,-.015571,
.016464,-.015,
.016759,-.014368,
.016939,-.013695,
.017,-.013,
.017,.013,
.016939,.013695,
.016759,.014368,
.016464,.015,
.016064,.015571,
.015571,.016064,
.015,.016464,
.014368,.016759,
.013695,.016939,
.013,.017,
0.0*
%
%ADD45MACRO45*%
%AMMACRO43*
4,1,6,.025,.0135,
.005,-.0065,
.005,-.0135,
-.005,-.0135,
-.005,-.0065,
-.025,.0135,
.025,.0135,
0.0*
%
%ADD43MACRO43*%
%AMMACRO23*
4,1,40,.017,-.013,
.017,.013,
.016939,.013695,
.016759,.014368,
.016464,.015,
.016064,.015571,
.015571,.016064,
.015,.016464,
.014368,.016759,
.013695,.016939,
.013,.017,
-.013,.017,
-.013695,.016939,
-.014368,.016759,
-.015,.016464,
-.015571,.016064,
-.016064,.015571,
-.016464,.015,
-.016759,.014368,
-.016939,.013695,
-.017,.013,
-.017,-.013,
-.016939,-.013695,
-.016759,-.014368,
-.016464,-.015,
-.016064,-.015571,
-.015571,-.016064,
-.015,-.016464,
-.014368,-.016759,
-.013695,-.016939,
-.013,-.017,
.013,-.017,
.013695,-.016939,
.014368,-.016759,
.015,-.016464,
.015571,-.016064,
.016064,-.015571,
.016464,-.015,
.016759,-.014368,
.016939,-.013695,
.017,-.013,
0.0*
%
%ADD23MACRO23*%
%AMMACRO38*
4,1,20,-.0635,.1075,
-.049,.1075,
-.049,.118,
-.0395,.118,
-.0395,.1075,
.0395,.1075,
.0395,.118,
.049,.118,
.049,.1075,
.0635,.1075,
.0635,-.1075,
.049,-.1075,
.049,-.118,
.0395,-.118,
.0395,-.1075,
-.0395,-.1075,
-.0395,-.118,
-.049,-.118,
-.049,-.1075,
-.0635,-.1075,
-.0635,.1075,
0.0*
%
%ADD38MACRO38*%
%AMMACRO34*
4,1,40,-.007,-.011,
.007,-.011,
.007695,-.010939,
.008368,-.010759,
.009,-.010464,
.009571,-.010064,
.010064,-.009571,
.010464,-.009,
.010759,-.008368,
.010939,-.007695,
.011,-.007,
.011,.007,
.010939,.007695,
.010759,.008368,
.010464,.009,
.010064,.009571,
.009571,.010064,
.009,.010464,
.008368,.010759,
.007695,.010939,
.007,.011,
-.007,.011,
-.007695,.010939,
-.008368,.010759,
-.009,.010464,
-.009571,.010064,
-.010064,.009571,
-.010464,.009,
-.010759,.008368,
-.010939,.007695,
-.011,.007,
-.011,-.007,
-.010939,-.007695,
-.010759,-.008368,
-.010464,-.009,
-.010064,-.009571,
-.009571,-.010064,
-.009,-.010464,
-.008368,-.010759,
-.007695,-.010939,
-.007,-.011,
0.0*
%
%ADD34MACRO34*%
%AMMACRO28*
4,1,40,-.008,-.012,
.008,-.012,
.008695,-.011939,
.009368,-.011759,
.01,-.011464,
.010571,-.011064,
.011064,-.010571,
.011464,-.01,
.011759,-.009368,
.011939,-.008695,
.012,-.008,
.012,.008,
.011939,.008695,
.011759,.009368,
.011464,.01,
.011064,.010571,
.010571,.011064,
.01,.011464,
.009368,.011759,
.008695,.011939,
.008,.012,
-.008,.012,
-.008695,.011939,
-.009368,.011759,
-.01,.011464,
-.010571,.011064,
-.011064,.010571,
-.011464,.01,
-.011759,.009368,
-.011939,.008695,
-.012,.008,
-.012,-.008,
-.011939,-.008695,
-.011759,-.009368,
-.011464,-.01,
-.011064,-.010571,
-.010571,-.011064,
-.01,-.011464,
-.009368,-.011759,
-.008695,-.011939,
-.008,-.012,
0.0*
%
%ADD28MACRO28*%
%AMMACRO19*
4,1,40,.012,-.008,
.012,.008,
.011939,.008695,
.011759,.009368,
.011464,.01,
.011064,.010571,
.010571,.011064,
.01,.011464,
.009368,.011759,
.008695,.011939,
.008,.012,
-.008,.012,
-.008695,.011939,
-.009368,.011759,
-.01,.011464,
-.010571,.011064,
-.011064,.010571,
-.011464,.01,
-.011759,.009368,
-.011939,.008695,
-.012,.008,
-.012,-.008,
-.011939,-.008695,
-.011759,-.009368,
-.011464,-.01,
-.011064,-.010571,
-.010571,-.011064,
-.01,-.011464,
-.009368,-.011759,
-.008695,-.011939,
-.008,-.012,
.008,-.012,
.008695,-.011939,
.009368,-.011759,
.01,-.011464,
.010571,-.011064,
.011064,-.010571,
.011464,-.01,
.011759,-.009368,
.011939,-.008695,
.012,-.008,
0.0*
%
%ADD19MACRO19*%
%AMMACRO27*
4,1,40,-.011,.007,
-.011,-.007,
-.010939,-.007695,
-.010759,-.008368,
-.010464,-.009,
-.010064,-.009571,
-.009571,-.010064,
-.009,-.010464,
-.008368,-.010759,
-.007695,-.010939,
-.007,-.011,
.007,-.011,
.007695,-.010939,
.008368,-.010759,
.009,-.010464,
.009571,-.010064,
.010064,-.009571,
.010464,-.009,
.010759,-.008368,
.010939,-.007695,
.011,-.007,
.011,.007,
.010939,.007695,
.010759,.008368,
.010464,.009,
.010064,.009571,
.009571,.010064,
.009,.010464,
.008368,.010759,
.007695,.010939,
.007,.011,
-.007,.011,
-.007695,.010939,
-.008368,.010759,
-.009,.010464,
-.009571,.010064,
-.010064,.009571,
-.010464,.009,
-.010759,.008368,
-.010939,.007695,
-.011,.007,
0.0*
%
%ADD27MACRO27*%
%ADD58C,.02*%
%ADD59C,.006*%
G75*
%LPD*%
G75*
G54D10*
X26087Y-114844D03*
X26435Y373984D03*
X175335Y62719D03*
Y189062D03*
X547104Y69007D03*
Y195351D03*
X696192Y373984D03*
G54D11*
X25596Y316176D03*
X237013Y17712D03*
X287407Y345704D03*
G54D20*
X63000Y303489D03*
X103000Y284300D03*
X100500Y342489D03*
X109500Y286800D03*
X130000Y295300D03*
X203600Y299800D03*
X290000Y163300D03*
G54D30*
X104955Y293900D03*
X102985D03*
X101015D03*
X99045D03*
Y303100D03*
X101015D03*
X102985D03*
X104955D03*
G54D21*
X63000Y299889D03*
X103000Y280700D03*
X100500Y338889D03*
X109500Y283200D03*
X130000Y291700D03*
X203600Y296200D03*
X290000Y159700D03*
G54D12*
X22401Y341025D03*
X291000Y22500D03*
X316610Y341025D03*
G54D13*
X56200Y325189D03*
X67200Y302689D03*
X207300Y300200D03*
X233700Y67000D03*
Y75000D03*
Y71000D03*
Y122000D03*
Y126000D03*
Y138500D03*
Y130000D03*
Y134500D03*
Y175500D03*
Y183500D03*
Y179500D03*
Y238500D03*
Y243000D03*
Y230500D03*
Y234500D03*
Y247000D03*
G54D31*
X100200Y310000D03*
G54D22*
X71500Y315689D03*
G54D40*
X176311Y301700D03*
X294000Y154200D03*
X298000D03*
G54D23*
X58000Y320489D03*
X169500Y336300D03*
X196000Y341300D03*
G54D41*
X176311Y298300D03*
X294000Y150800D03*
X298000D03*
G54D32*
X103800Y310000D03*
G54D14*
X53500Y320689D03*
X71000Y294189D03*
X66750Y289689D03*
X59000Y304189D03*
X68000Y339189D03*
X58000Y337439D03*
X77500Y338000D03*
X95000Y289000D03*
X94500Y303100D03*
X96500Y332500D03*
X117913Y287300D03*
X122500Y285500D03*
X110500Y306000D03*
X123500Y304700D03*
X128500Y304500D03*
X162311Y298500D03*
X194811Y303500D03*
X207500Y296250D03*
X258000Y160500D03*
X299500Y144900D03*
X298500Y254000D03*
G54D50*
X265551Y64724D03*
Y173386D03*
X311614Y31870D03*
G54D33*
X100200Y317000D03*
Y321000D03*
X298200Y249000D03*
G54D15*
X58200Y331189D03*
X65800D03*
X76700Y285689D03*
X84300D03*
X76700Y293689D03*
X84300D03*
X76700Y301689D03*
X84300D03*
X76700Y331189D03*
X84300D03*
X255200Y296000D03*
Y304000D03*
X262800Y296000D03*
Y304000D03*
G54D42*
X185811Y298250D03*
G54D51*
X265551Y143464D03*
Y252126D03*
G54D24*
X58000Y314889D03*
X169500Y330700D03*
X196000Y335700D03*
G54D34*
X96800Y317000D03*
Y321000D03*
X294800Y249000D03*
G54D43*
X185811Y300750D03*
G54D16*
X63300Y294189D03*
X67300Y298689D03*
X70800Y345000D03*
X96800Y325000D03*
X192111Y299500D03*
X204111Y304000D03*
X294800Y245000D03*
G54D52*
X283268Y63346D03*
Y144842D03*
Y172008D03*
Y253504D03*
G54D25*
X71500Y315689D03*
X67900D03*
X75100D03*
X185811Y310500D03*
X181811D03*
Y318500D03*
X185811Y314500D03*
Y326500D03*
Y322500D03*
Y318500D03*
X181811Y326500D03*
Y322500D03*
Y314500D03*
X189811Y310500D03*
Y318500D03*
Y322500D03*
Y326500D03*
Y314500D03*
G54D26*
X62000Y337489D03*
X95000Y280800D03*
X99000D03*
X114500Y281800D03*
X119000Y280300D03*
Y308300D03*
X115000D03*
X123500D03*
X127500D03*
X168311Y298300D03*
X199811Y296300D03*
X296000Y132300D03*
Y139800D03*
G54D35*
X123100Y294015D03*
Y292045D03*
X113900D03*
Y294015D03*
X123100Y297955D03*
Y295985D03*
X113900D03*
Y297955D03*
G54D17*
X66700Y294189D03*
X70700Y298689D03*
X74200Y345000D03*
X100200Y325000D03*
X195511Y299500D03*
X207511Y304000D03*
X298200Y245000D03*
G54D53*
X297000Y118200D03*
G54D44*
X206943Y324000D03*
X232057D03*
G54D27*
X62000Y340889D03*
X95000Y284200D03*
X99000D03*
X114500Y285200D03*
X119000Y283700D03*
Y311700D03*
X115000D03*
X123500D03*
X127500D03*
X168311Y301700D03*
X199811Y299700D03*
X296000Y135700D03*
Y143200D03*
G54D45*
X208200Y292000D03*
G54D18*
X67565Y309589D03*
X69530D03*
X71500D03*
Y321789D03*
X69530D03*
X67565D03*
X73470Y309589D03*
X75435D03*
Y321789D03*
X73470D03*
G54D36*
X107325Y320089D03*
X109880D03*
X112440D03*
X115000D03*
X117560D03*
X120120D03*
X122675D03*
Y342289D03*
X120120D03*
X117560D03*
X115000D03*
X112440D03*
X109880D03*
X107325D03*
G54D54*
X297000Y123800D03*
G54D19*
X70800Y302689D03*
X59800Y325189D03*
X210900Y300200D03*
X237300Y67000D03*
Y75000D03*
Y71000D03*
Y122000D03*
Y126000D03*
Y138500D03*
Y130000D03*
Y134500D03*
Y175500D03*
Y183500D03*
Y179500D03*
Y238500D03*
Y243000D03*
Y230500D03*
Y234500D03*
Y247000D03*
G54D28*
X71500Y329389D03*
X165000Y308200D03*
X249000Y144200D03*
Y252700D03*
G54D37*
X139000Y312200D03*
Y319800D03*
Y329200D03*
Y336800D03*
X147000Y312200D03*
X155000D03*
X147000Y319800D03*
X155000D03*
Y329200D03*
Y336800D03*
X147000Y329200D03*
Y336800D03*
X163000Y329200D03*
Y336800D03*
X189500Y336200D03*
Y343800D03*
G54D55*
X295440Y162250D03*
X298000D03*
X300560D03*
Y168750D03*
X295440D03*
G54D46*
X213800Y292000D03*
G54D38*
X185811Y318500D03*
G54D29*
X71500Y332989D03*
X165000Y311800D03*
X249000Y147800D03*
Y256300D03*
G54D47*
X230410Y154660D03*
Y157220D03*
Y159780D03*
Y162340D03*
X246590D03*
Y159780D03*
Y157220D03*
Y154660D03*
G54D56*
X302000Y290500D03*
Y300500D03*
Y310500D03*
G54D39*
X176168Y308657D03*
Y310626D03*
Y312594D03*
Y314563D03*
Y316531D03*
Y318500D03*
Y320469D03*
Y322437D03*
Y324406D03*
Y326374D03*
Y328343D03*
X195454Y310626D03*
Y308657D03*
Y326374D03*
Y324406D03*
Y322437D03*
Y320469D03*
Y318500D03*
Y316531D03*
Y314563D03*
Y312594D03*
Y328343D03*
G54D48*
X256594Y68661D03*
Y70629D03*
Y72598D03*
Y74566D03*
Y84409D03*
Y86377D03*
Y88346D03*
Y90314D03*
Y92283D03*
Y94251D03*
Y96220D03*
Y98188D03*
Y100157D03*
Y102125D03*
Y104094D03*
Y106063D03*
Y108031D03*
Y110000D03*
Y111968D03*
Y113937D03*
Y115905D03*
Y117874D03*
Y119842D03*
Y121811D03*
Y123779D03*
Y125748D03*
Y127716D03*
Y129685D03*
Y131653D03*
Y133622D03*
Y135590D03*
Y137559D03*
Y139527D03*
Y177323D03*
Y179291D03*
Y181260D03*
Y183228D03*
Y193071D03*
Y195039D03*
Y197008D03*
Y198976D03*
Y200945D03*
Y202913D03*
Y204882D03*
Y206850D03*
Y208819D03*
Y210787D03*
Y212756D03*
Y214725D03*
Y216693D03*
Y218662D03*
Y220630D03*
Y222599D03*
Y224567D03*
Y226536D03*
Y228504D03*
Y230473D03*
Y232441D03*
Y234410D03*
Y236378D03*
Y238347D03*
Y240315D03*
Y242284D03*
Y244252D03*
Y246221D03*
Y248189D03*
X286319Y67677D03*
Y69645D03*
Y71614D03*
Y73582D03*
Y75551D03*
Y85393D03*
Y87362D03*
Y89330D03*
Y91299D03*
Y93267D03*
Y95236D03*
Y97204D03*
Y99173D03*
Y101141D03*
Y103110D03*
Y105078D03*
Y107047D03*
Y109015D03*
Y110984D03*
Y112952D03*
Y114921D03*
Y116889D03*
Y118858D03*
Y120826D03*
Y122795D03*
Y124763D03*
Y126732D03*
Y128700D03*
Y130669D03*
Y132637D03*
Y134606D03*
Y136574D03*
Y138543D03*
Y140511D03*
Y176339D03*
Y178307D03*
Y180276D03*
Y182244D03*
Y184213D03*
Y194055D03*
Y196024D03*
Y197992D03*
Y199961D03*
Y201929D03*
Y203898D03*
Y205866D03*
Y207835D03*
Y209803D03*
Y211772D03*
Y213740D03*
Y215709D03*
Y217677D03*
Y219646D03*
Y221614D03*
Y223583D03*
Y225551D03*
Y227520D03*
Y229488D03*
Y231457D03*
Y233425D03*
Y235394D03*
Y237362D03*
Y239331D03*
Y241299D03*
Y243268D03*
Y245236D03*
Y247205D03*
Y249173D03*
G54D57*
X311614Y185414D03*
G54D58*
G01X-176139Y-183003D02*
G02I-12000J0D01*
G01X-181289D02*
G02I-6850J0D01*
G01X-172139D02*
X-204139D01*
G01X-188139Y-199003D02*
Y-167003D01*
G01X-172139Y-199003D02*
Y-279003D01*
G01D02*
X1178561D01*
G01X-172139Y-234503D02*
X1178561D01*
G01X-172139Y-199003D02*
X1178561D01*
G01X391061D02*
Y-279003D01*
G01X528561Y-199003D02*
Y-279003D01*
G01X643561Y-199003D02*
Y-279003D01*
G01X811061Y-199003D02*
Y-279003D01*
G01X981061Y-199003D02*
Y-279003D01*
G01X1178561Y-199003D02*
Y-279003D01*
G01X1210561Y-183003D02*
X1178561D01*
G01X1206561D02*
G02I-12000J0D01*
G01X1201411D02*
G02I-6850J0D01*
G01X1194561Y-199003D02*
Y-167003D01*
G54D49*
X249000Y315100D03*
Y339900D03*
G54D59*
G01X-148956Y-251503D02*
Y-269003D01*
X-140222D01*
G01X-127089Y-257337D02*
Y-269003D01*
G01Y-252670D02*
X-127526Y-252378D01*
Y-251795D01*
X-127089Y-251503D01*
X-126652Y-251795D01*
Y-252378D01*
X-127089Y-252670D01*
G01X-112646Y-273378D02*
X-111117Y-274545D01*
X-109371Y-274836D01*
X-107843Y-274545D01*
X-106532Y-273087D01*
X-105659Y-271045D01*
Y-257337D01*
G01Y-259670D02*
X-106532Y-258503D01*
X-107843Y-257628D01*
X-109371Y-257337D01*
X-111117Y-257920D01*
X-112209Y-259086D01*
X-113083Y-261128D01*
X-113519Y-263170D01*
X-113301Y-264920D01*
X-112427Y-266962D01*
X-111117Y-268420D01*
X-109371Y-269003D01*
X-108061Y-268711D01*
X-106532Y-267545D01*
X-105659Y-266379D01*
G01X-95801Y-269003D02*
Y-251503D01*
G01Y-259961D02*
X-94709Y-258503D01*
X-93617Y-257628D01*
X-91871Y-257337D01*
X-90561Y-257628D01*
X-89032Y-258795D01*
X-88377Y-260545D01*
Y-269003D01*
G01X-74589Y-251503D02*
Y-269003D01*
G01X-77646Y-257337D02*
X-71532D01*
G01X-60801Y-269003D02*
Y-257337D01*
G01Y-260253D02*
X-59927Y-258795D01*
X-58617Y-257628D01*
X-56871Y-257337D01*
X-55343Y-257628D01*
X-54032Y-258795D01*
X-53377Y-260836D01*
Y-269003D01*
G01X-39589Y-257337D02*
Y-269003D01*
G01Y-252670D02*
X-40026Y-252378D01*
Y-251795D01*
X-39589Y-251503D01*
X-39152Y-251795D01*
Y-252378D01*
X-39589Y-252670D01*
G01X-25801Y-269003D02*
Y-257337D01*
G01Y-260253D02*
X-24927Y-258795D01*
X-23617Y-257628D01*
X-21871Y-257337D01*
X-20343Y-257628D01*
X-19032Y-258795D01*
X-18377Y-260836D01*
Y-269003D01*
G01X-7646Y-273378D02*
X-6117Y-274545D01*
X-4371Y-274836D01*
X-2843Y-274545D01*
X-1532Y-273087D01*
X-659Y-271045D01*
Y-257337D01*
G01Y-259670D02*
X-1532Y-258503D01*
X-2843Y-257628D01*
X-4371Y-257337D01*
X-6117Y-257920D01*
X-7209Y-259086D01*
X-8083Y-261128D01*
X-8519Y-263170D01*
X-8301Y-264920D01*
X-7427Y-266962D01*
X-6117Y-268420D01*
X-4371Y-269003D01*
X-3061Y-268711D01*
X-1532Y-267545D01*
X-659Y-266379D01*
G01X26044Y-269003D02*
Y-251503D01*
X31284D01*
X33031Y-252378D01*
X34341Y-254420D01*
X34778Y-256753D01*
X34341Y-259086D01*
X33249Y-260836D01*
X31284Y-261712D01*
X26044D01*
G01X42452Y-251503D02*
X47911Y-269003D01*
X53370Y-251503D01*
G01X65411D02*
Y-269003D01*
G01X60389Y-251503D02*
X70433D01*
G01X94734Y-269003D02*
Y-251503D01*
X100411Y-266086D01*
X106088Y-251503D01*
Y-269003D01*
G01X117911Y-269586D02*
X117474Y-269295D01*
Y-268711D01*
X117911Y-268420D01*
X118348Y-268711D01*
Y-269295D01*
X117911Y-269586D01*
G01X131263Y-254420D02*
X132573Y-252670D01*
X134101Y-251795D01*
X135848Y-251503D01*
X138031Y-252086D01*
X139559Y-253545D01*
X139996Y-255294D01*
X139778Y-257045D01*
X138904Y-258503D01*
X134538Y-261420D01*
X132573Y-263461D01*
X131263Y-266379D01*
X130826Y-269003D01*
X139996D01*
G01X164952D02*
X170411Y-251503D01*
X175870Y-269003D01*
G01X173904Y-262878D02*
X166917D01*
G01X191841Y-251503D02*
Y-269003D01*
G01Y-266379D02*
X190968Y-267837D01*
X189657Y-268711D01*
X188129Y-269003D01*
X186383Y-268420D01*
X185073Y-266962D01*
X184199Y-265212D01*
X183981Y-263170D01*
X184199Y-261128D01*
X185073Y-259378D01*
X186383Y-257920D01*
X188129Y-257337D01*
X189657Y-257628D01*
X190749Y-258212D01*
X191841Y-259378D01*
G01X209341Y-269003D02*
Y-257337D01*
G01Y-259378D02*
X208468Y-258212D01*
X207157Y-257628D01*
X205629Y-257337D01*
X204101Y-257920D01*
X202791Y-259086D01*
X201917Y-260836D01*
X201481Y-263170D01*
X201917Y-265503D01*
X202791Y-267253D01*
X204101Y-268420D01*
X205629Y-269003D01*
X207157Y-268711D01*
X208468Y-267837D01*
X209341Y-266670D01*
G01X218981Y-274836D02*
Y-257337D01*
G01Y-259961D02*
X220073Y-258503D01*
X221164Y-257628D01*
X222911Y-257337D01*
X224439Y-257628D01*
X225968Y-259086D01*
X226623Y-261128D01*
X226841Y-263170D01*
X226623Y-265212D01*
X225968Y-267253D01*
X224657Y-268420D01*
X222911Y-269003D01*
X221383Y-268711D01*
X219854Y-267837D01*
X218981Y-266670D01*
G01X240411Y-251503D02*
Y-269003D01*
G01X237354Y-257337D02*
X243468D01*
G01X257911Y-269003D02*
X256601Y-268711D01*
X255291Y-267545D01*
X254417Y-265503D01*
X253981Y-263170D01*
X254417Y-260836D01*
X255291Y-258795D01*
X256601Y-257628D01*
X257911Y-257337D01*
X259221Y-257628D01*
X260531Y-258795D01*
X261404Y-260836D01*
X261623Y-263170D01*
X261404Y-265503D01*
X260531Y-267545D01*
X259221Y-268711D01*
X257911Y-269003D01*
G01X272354D02*
Y-257337D01*
G01Y-259670D02*
X273446Y-258503D01*
X274538Y-257628D01*
X276066Y-257337D01*
X277157Y-257628D01*
X278468Y-258503D01*
G01X315214Y-252962D02*
X313904Y-252086D01*
X312376Y-251503D01*
X310629D01*
X308664Y-252378D01*
X307136Y-253836D01*
X306044Y-255587D01*
X305171Y-258503D01*
X304952Y-261128D01*
X305389Y-263753D01*
X306044Y-265503D01*
X307354Y-267253D01*
X308883Y-268420D01*
X310411Y-269003D01*
X311939D01*
X313468Y-268420D01*
X314778Y-267545D01*
X315870Y-266379D01*
G01X331841Y-269003D02*
Y-257337D01*
G01Y-259378D02*
X330968Y-258212D01*
X329657Y-257628D01*
X328129Y-257337D01*
X326601Y-257920D01*
X325291Y-259086D01*
X324417Y-260836D01*
X323981Y-263170D01*
X324417Y-265503D01*
X325291Y-267253D01*
X326601Y-268420D01*
X328129Y-269003D01*
X329657Y-268711D01*
X330968Y-267837D01*
X331841Y-266670D01*
G01X342354Y-269003D02*
Y-257337D01*
G01Y-259670D02*
X343446Y-258503D01*
X344538Y-257628D01*
X346066Y-257337D01*
X347157Y-257628D01*
X348468Y-258503D01*
G01X366841Y-251503D02*
Y-269003D01*
G01Y-266379D02*
X365968Y-267837D01*
X364657Y-268711D01*
X363129Y-269003D01*
X361383Y-268420D01*
X360073Y-266962D01*
X359199Y-265212D01*
X358981Y-263170D01*
X359199Y-261128D01*
X360073Y-259378D01*
X361383Y-257920D01*
X363129Y-257337D01*
X364657Y-257628D01*
X365749Y-258212D01*
X366841Y-259378D01*
G01X68484Y-224003D02*
Y-206503D01*
X74161Y-221086D01*
X79838Y-206503D01*
Y-224003D01*
G01X91661D02*
X90351Y-223711D01*
X89041Y-222545D01*
X88167Y-220503D01*
X87731Y-218170D01*
X88167Y-215836D01*
X89041Y-213795D01*
X90351Y-212628D01*
X91661Y-212337D01*
X92971Y-212628D01*
X94281Y-213795D01*
X95154Y-215836D01*
X95373Y-218170D01*
X95154Y-220503D01*
X94281Y-222545D01*
X92971Y-223711D01*
X91661Y-224003D01*
G01X113091Y-206503D02*
Y-224003D01*
G01Y-221379D02*
X112218Y-222837D01*
X110907Y-223711D01*
X109379Y-224003D01*
X107633Y-223420D01*
X106323Y-221962D01*
X105449Y-220212D01*
X105231Y-218170D01*
X105449Y-216128D01*
X106323Y-214378D01*
X107633Y-212920D01*
X109379Y-212337D01*
X110907Y-212628D01*
X111999Y-213212D01*
X113091Y-214378D01*
G01X123386Y-216128D02*
X130373D01*
X129718Y-214086D01*
X128626Y-212920D01*
X127098Y-212337D01*
X125569Y-212628D01*
X124259Y-213503D01*
X123386Y-215545D01*
X122949Y-217295D01*
Y-219045D01*
X123386Y-220795D01*
X124478Y-222545D01*
X125788Y-223711D01*
X127316Y-224003D01*
X128844Y-223420D01*
X130373Y-221670D01*
G01X144161Y-224003D02*
Y-206503D01*
G01X424761Y-269003D02*
Y-251503D01*
X422141Y-255003D01*
G01Y-269003D02*
X427381D01*
G01X437458Y-266379D02*
X438767Y-267837D01*
X440296Y-268711D01*
X442261Y-269003D01*
X444226Y-268420D01*
X445754Y-267253D01*
X446846Y-265212D01*
X447064Y-262878D01*
X446628Y-260545D01*
X445536Y-259086D01*
X444007Y-257920D01*
X442479Y-257628D01*
X440951Y-257920D01*
X438986Y-259086D01*
X439641Y-251503D01*
X445536D01*
G01X459324Y-269003D02*
X459761Y-265212D01*
X460416Y-262003D01*
X461289Y-259086D01*
X462381Y-255878D01*
X464128Y-251503D01*
X455394D01*
G01X472458Y-266379D02*
X473767Y-267837D01*
X475296Y-268711D01*
X477261Y-269003D01*
X479226Y-268420D01*
X480754Y-267253D01*
X481846Y-265212D01*
X482064Y-262878D01*
X481628Y-260545D01*
X480536Y-259086D01*
X479007Y-257920D01*
X477479Y-257628D01*
X475951Y-257920D01*
X473986Y-259086D01*
X474641Y-251503D01*
X480536D01*
G01X494761D02*
X493014Y-252086D01*
X491704Y-253545D01*
X490831Y-255294D01*
X490176Y-257628D01*
X489958Y-260253D01*
X490176Y-262878D01*
X490831Y-265212D01*
X491704Y-266962D01*
X493014Y-268420D01*
X494761Y-269003D01*
X496507Y-268420D01*
X497818Y-266962D01*
X498691Y-265212D01*
X499346Y-262878D01*
X499564Y-260253D01*
X499346Y-257628D01*
X498691Y-255294D01*
X497818Y-253545D01*
X496507Y-252086D01*
X494761Y-251503D01*
G01X411644Y-224003D02*
Y-206503D01*
X416884D01*
X418631Y-207378D01*
X419941Y-209420D01*
X420378Y-211753D01*
X419941Y-214086D01*
X418849Y-215836D01*
X416884Y-216712D01*
X411644D01*
G01X438314Y-207962D02*
X437004Y-207086D01*
X435476Y-206503D01*
X433729D01*
X431764Y-207378D01*
X430236Y-208836D01*
X429144Y-210587D01*
X428271Y-213503D01*
X428052Y-216128D01*
X428489Y-218753D01*
X429144Y-220503D01*
X430454Y-222253D01*
X431983Y-223420D01*
X433511Y-224003D01*
X435039D01*
X436568Y-223420D01*
X437878Y-222545D01*
X438970Y-221379D01*
G01X452757Y-214670D02*
X453631Y-213795D01*
X454286Y-212337D01*
X454723Y-210294D01*
X454286Y-208545D01*
X453413Y-207378D01*
X451884Y-206503D01*
X445989D01*
Y-224003D01*
X453194D01*
X454723Y-222837D01*
X455596Y-221086D01*
X456033Y-219045D01*
X455596Y-217003D01*
X454286Y-215253D01*
X452757Y-214670D01*
X445989D01*
G01X461961Y-229836D02*
X475061D01*
G01X480989Y-224003D02*
Y-206503D01*
X491033Y-224003D01*
Y-206503D01*
G01X503511Y-224003D02*
X501764Y-223711D01*
X500236Y-222545D01*
X498926Y-220795D01*
X498052Y-218753D01*
X497616Y-216420D01*
Y-214086D01*
X498052Y-211753D01*
X498926Y-209711D01*
X500236Y-207962D01*
X501764Y-206795D01*
X503511Y-206503D01*
X505257Y-206795D01*
X506786Y-207962D01*
X508096Y-209711D01*
X508970Y-211753D01*
X509406Y-214086D01*
Y-216420D01*
X508970Y-218753D01*
X508096Y-220795D01*
X506786Y-222545D01*
X505257Y-223711D01*
X503511Y-224003D01*
G01X554352Y-206503D02*
X559811Y-224003D01*
X565270Y-206503D01*
G01X581678Y-224003D02*
X572944D01*
Y-206503D01*
X581678D01*
G01X578184Y-214961D02*
X572944D01*
G01X590444Y-224003D02*
Y-206503D01*
X595903D01*
X597649Y-207378D01*
X598741Y-208545D01*
X599178Y-210878D01*
X598741Y-213212D01*
X597431Y-214670D01*
X595903Y-215545D01*
X590444D01*
G01X595903D02*
X599178Y-224003D01*
G01X612311Y-224586D02*
X611874Y-224295D01*
Y-223711D01*
X612311Y-223420D01*
X612748Y-223711D01*
Y-224295D01*
X612311Y-224586D01*
G01X586061Y-269003D02*
Y-251503D01*
X583441Y-255003D01*
G01Y-269003D02*
X588681D01*
G01X692261Y-251503D02*
Y-269003D01*
G01X687239Y-251503D02*
X697283D01*
G01X704084Y-269003D02*
Y-251503D01*
X709761Y-266086D01*
X715438Y-251503D01*
Y-269003D01*
G01X721802D02*
X727261Y-251503D01*
X732720Y-269003D01*
G01X730754Y-262878D02*
X723767D01*
G01X740176Y-266670D02*
X741923Y-268128D01*
X743888Y-269003D01*
X745634D01*
X747381Y-268128D01*
X748691Y-266670D01*
X749346Y-264628D01*
X748909Y-262587D01*
X747818Y-260836D01*
X745853Y-259670D01*
X743233Y-259086D01*
X741704Y-257920D01*
X741049Y-255878D01*
X741486Y-253836D01*
X742578Y-252378D01*
X744106Y-251503D01*
X745634D01*
X747163Y-252086D01*
X748473Y-253545D01*
G01X757458Y-269003D02*
Y-251503D01*
G01X765754D02*
X757458Y-262295D01*
G01X767064Y-269003D02*
X761169Y-257337D01*
G01X687894Y-206503D02*
Y-224003D01*
X696628D01*
G01X713691D02*
Y-212337D01*
G01Y-214378D02*
X712818Y-213212D01*
X711507Y-212628D01*
X709979Y-212337D01*
X708451Y-212920D01*
X707141Y-214086D01*
X706267Y-215836D01*
X705831Y-218170D01*
X706267Y-220503D01*
X707141Y-222253D01*
X708451Y-223420D01*
X709979Y-224003D01*
X711507Y-223711D01*
X712818Y-222837D01*
X713691Y-221670D01*
G01X722676Y-229253D02*
X723986Y-229836D01*
X725733Y-229253D01*
X726824Y-228087D01*
X727698Y-226628D01*
X729007Y-221962D01*
X731846Y-212337D01*
G01X724859D02*
X729007Y-221962D01*
G01X741486Y-216128D02*
X748473D01*
X747818Y-214086D01*
X746726Y-212920D01*
X745198Y-212337D01*
X743669Y-212628D01*
X742359Y-213503D01*
X741486Y-215545D01*
X741049Y-217295D01*
Y-219045D01*
X741486Y-220795D01*
X742578Y-222545D01*
X743888Y-223711D01*
X745416Y-224003D01*
X746944Y-223420D01*
X748473Y-221670D01*
G01X759204Y-224003D02*
Y-212337D01*
G01Y-214670D02*
X760296Y-213503D01*
X761388Y-212628D01*
X762916Y-212337D01*
X764007Y-212628D01*
X765318Y-213503D01*
G01X830008Y-224003D02*
Y-206503D01*
X834374D01*
X836121Y-207378D01*
X837431Y-208545D01*
X838523Y-210294D01*
X839396Y-212337D01*
X839614Y-215253D01*
X839396Y-218170D01*
X838523Y-220212D01*
X837431Y-221962D01*
X836121Y-223128D01*
X834374Y-224003D01*
X830008D01*
G01X849036Y-216128D02*
X856023D01*
X855368Y-214086D01*
X854276Y-212920D01*
X852748Y-212337D01*
X851219Y-212628D01*
X849909Y-213503D01*
X849036Y-215545D01*
X848599Y-217295D01*
Y-219045D01*
X849036Y-220795D01*
X850128Y-222545D01*
X851438Y-223711D01*
X852966Y-224003D01*
X854494Y-223420D01*
X856023Y-221670D01*
G01X866536Y-221962D02*
X867628Y-223128D01*
X869156Y-224003D01*
X870466D01*
X871776Y-223420D01*
X872649Y-222545D01*
X873086Y-221379D01*
X872868Y-219628D01*
X871994Y-218753D01*
X868064Y-217003D01*
X867191Y-214961D01*
X867628Y-213503D01*
X868501Y-212628D01*
X869811Y-212337D01*
X871121Y-212628D01*
X872431Y-213503D01*
G01X887311Y-212337D02*
Y-224003D01*
G01Y-207670D02*
X886874Y-207378D01*
Y-206795D01*
X887311Y-206503D01*
X887748Y-206795D01*
Y-207378D01*
X887311Y-207670D01*
G01X901754Y-228378D02*
X903283Y-229545D01*
X905029Y-229836D01*
X906557Y-229545D01*
X907868Y-228087D01*
X908741Y-226045D01*
Y-212337D01*
G01Y-214670D02*
X907868Y-213503D01*
X906557Y-212628D01*
X905029Y-212337D01*
X903283Y-212920D01*
X902191Y-214086D01*
X901317Y-216128D01*
X900881Y-218170D01*
X901099Y-219920D01*
X901973Y-221962D01*
X903283Y-223420D01*
X905029Y-224003D01*
X906339Y-223711D01*
X907868Y-222545D01*
X908741Y-221379D01*
G01X918599Y-224003D02*
Y-212337D01*
G01Y-215253D02*
X919473Y-213795D01*
X920783Y-212628D01*
X922529Y-212337D01*
X924057Y-212628D01*
X925368Y-213795D01*
X926023Y-215836D01*
Y-224003D01*
G01X936536Y-216128D02*
X943523D01*
X942868Y-214086D01*
X941776Y-212920D01*
X940248Y-212337D01*
X938719Y-212628D01*
X937409Y-213503D01*
X936536Y-215545D01*
X936099Y-217295D01*
Y-219045D01*
X936536Y-220795D01*
X937628Y-222545D01*
X938938Y-223711D01*
X940466Y-224003D01*
X941994Y-223420D01*
X943523Y-221670D01*
G01X954254Y-224003D02*
Y-212337D01*
G01Y-214670D02*
X955346Y-213503D01*
X956438Y-212628D01*
X957966Y-212337D01*
X959057Y-212628D01*
X960368Y-213503D01*
G01X874194Y-265503D02*
X875286Y-267253D01*
X876596Y-268420D01*
X878124Y-269003D01*
X879871Y-268420D01*
X881181Y-267253D01*
X882491Y-265503D01*
X882928Y-263170D01*
Y-251503D01*
G01X896061Y-269003D02*
X894314Y-268711D01*
X892786Y-267545D01*
X891476Y-265795D01*
X890602Y-263753D01*
X890166Y-261420D01*
Y-259086D01*
X890602Y-256753D01*
X891476Y-254711D01*
X892786Y-252962D01*
X894314Y-251795D01*
X896061Y-251503D01*
X897807Y-251795D01*
X899336Y-252962D01*
X900646Y-254711D01*
X901520Y-256753D01*
X901956Y-259086D01*
Y-261420D01*
X901520Y-263753D01*
X900646Y-265795D01*
X899336Y-267545D01*
X897807Y-268711D01*
X896061Y-269003D01*
G01X913561D02*
Y-261128D01*
X909194Y-251503D01*
G01X917928D02*
X913561Y-261128D01*
G01X1001011Y-269003D02*
Y-251503D01*
X998391Y-255003D01*
G01Y-269003D02*
X1003631D01*
G01X1014363Y-254420D02*
X1015673Y-252670D01*
X1017201Y-251795D01*
X1018948Y-251503D01*
X1021131Y-252086D01*
X1022659Y-253545D01*
X1023096Y-255294D01*
X1022878Y-257045D01*
X1022004Y-258503D01*
X1017638Y-261420D01*
X1015673Y-263461D01*
X1014363Y-266379D01*
X1013926Y-269003D01*
X1023096D01*
G01X1032081Y-269586D02*
X1039941Y-251503D01*
G01X1048708Y-265503D02*
X1050017Y-267545D01*
X1051764Y-268711D01*
X1053729Y-269003D01*
X1055476Y-268711D01*
X1057223Y-267253D01*
X1058314Y-265503D01*
X1058533Y-263753D01*
X1058096Y-261712D01*
X1056568Y-260253D01*
X1055039Y-259670D01*
X1053074D01*
G01X1055039D02*
X1056349Y-258795D01*
X1057441Y-257337D01*
X1057878Y-255587D01*
X1057441Y-253836D01*
X1056349Y-252378D01*
X1054384Y-251503D01*
X1052419Y-251795D01*
X1050454Y-252962D01*
G01X1071011Y-251503D02*
X1069264Y-252086D01*
X1067954Y-253545D01*
X1067081Y-255294D01*
X1066426Y-257628D01*
X1066208Y-260253D01*
X1066426Y-262878D01*
X1067081Y-265212D01*
X1067954Y-266962D01*
X1069264Y-268420D01*
X1071011Y-269003D01*
X1072757Y-268420D01*
X1074068Y-266962D01*
X1074941Y-265212D01*
X1075596Y-262878D01*
X1075814Y-260253D01*
X1075596Y-257628D01*
X1074941Y-255294D01*
X1074068Y-253545D01*
X1072757Y-252086D01*
X1071011Y-251503D01*
G01X1084581Y-269586D02*
X1092441Y-251503D01*
G01X1101863Y-254420D02*
X1103173Y-252670D01*
X1104701Y-251795D01*
X1106448Y-251503D01*
X1108631Y-252086D01*
X1110159Y-253545D01*
X1110596Y-255294D01*
X1110378Y-257045D01*
X1109504Y-258503D01*
X1105138Y-261420D01*
X1103173Y-263461D01*
X1101863Y-266379D01*
X1101426Y-269003D01*
X1110596D01*
G01X1123511Y-251503D02*
X1121764Y-252086D01*
X1120454Y-253545D01*
X1119581Y-255294D01*
X1118926Y-257628D01*
X1118708Y-260253D01*
X1118926Y-262878D01*
X1119581Y-265212D01*
X1120454Y-266962D01*
X1121764Y-268420D01*
X1123511Y-269003D01*
X1125257Y-268420D01*
X1126568Y-266962D01*
X1127441Y-265212D01*
X1128096Y-262878D01*
X1128314Y-260253D01*
X1128096Y-257628D01*
X1127441Y-255294D01*
X1126568Y-253545D01*
X1125257Y-252086D01*
X1123511Y-251503D01*
G01X1141011Y-269003D02*
Y-251503D01*
X1138391Y-255003D01*
G01Y-269003D02*
X1143631D01*
G01X1154363Y-261712D02*
X1155891Y-259670D01*
X1157201Y-258503D01*
X1158948Y-257920D01*
X1160476Y-258503D01*
X1161568Y-259670D01*
X1162441Y-261420D01*
X1162659Y-263461D01*
X1162441Y-265212D01*
X1161568Y-266962D01*
X1160257Y-268420D01*
X1158729Y-269003D01*
X1156983Y-268420D01*
X1155454Y-266670D01*
X1154581Y-264045D01*
X1154363Y-261128D01*
X1154799Y-257337D01*
X1155454Y-255294D01*
X1156546Y-253253D01*
X1158074Y-251795D01*
X1159603Y-251503D01*
X1161131Y-252086D01*
X1162223Y-253545D01*
G01X1048708Y-224003D02*
Y-206503D01*
X1053074D01*
X1054821Y-207378D01*
X1056131Y-208545D01*
X1057223Y-210294D01*
X1058096Y-212337D01*
X1058314Y-215253D01*
X1058096Y-218170D01*
X1057223Y-220212D01*
X1056131Y-221962D01*
X1054821Y-223128D01*
X1053074Y-224003D01*
X1048708D01*
G01X1074941D02*
Y-212337D01*
G01Y-214378D02*
X1074068Y-213212D01*
X1072757Y-212628D01*
X1071229Y-212337D01*
X1069701Y-212920D01*
X1068391Y-214086D01*
X1067517Y-215836D01*
X1067081Y-218170D01*
X1067517Y-220503D01*
X1068391Y-222253D01*
X1069701Y-223420D01*
X1071229Y-224003D01*
X1072757Y-223711D01*
X1074068Y-222837D01*
X1074941Y-221670D01*
G01X1088511Y-206503D02*
Y-224003D01*
G01X1085454Y-212337D02*
X1091568D01*
G01X1102736Y-216128D02*
X1109723D01*
X1109068Y-214086D01*
X1107976Y-212920D01*
X1106448Y-212337D01*
X1104919Y-212628D01*
X1103609Y-213503D01*
X1102736Y-215545D01*
X1102299Y-217295D01*
Y-219045D01*
X1102736Y-220795D01*
X1103828Y-222545D01*
X1105138Y-223711D01*
X1106666Y-224003D01*
X1108194Y-223420D01*
X1109723Y-221670D01*
M02*
